FILE_TYPE = MACRO_DRAWING;
SET COLOR_WIRE YELLOW;
SET COLOR_PROP ORANGE;
SET COLOR_DOT WHITE;
SET COLOR_ARC YELLOW;
SET COLOR_BODY GREEN;
SET COLOR_NOTE PURPLE;
SET PROP_DISPLAY VALUE;
SET PAGE_NUMBER P248;
FORCEADD OFFPAGE..6
(-6200 3175);
FORCEPROP 2 LAST $XR1 151 
J 0
(-6600 3175);
DISPLAY 0.638298 (-6600 3175);
PAINT MONO (-6600 3175);
FORCEPROP 2 LAST $XR0 150 
J 0
(-6480 3175);
DISPLAY 0.638298 (-6480 3175);
PAINT MONO (-6480 3175);
FORCEPROP 2 LAST CDS_LIB standard
J 0
(-6200 3175);
DISPLAY INVISIBLE (-6200 3175);
FORCEPROP 1 LAST OFFPAGE TRUE
J 0
(-5875 3050);
DISPLAY 0.872340 (-5875 3050);
DISPLAY INVISIBLE (-5875 3050);
FORCEPROP 1 LAST COMMENT_BODY TRUE
J 0
(-6100 3100);
DISPLAY 0.872340 (-6100 3100);
PAINT GREEN (-6100 3100);
DISPLAY INVISIBLE (-6100 3100);
FORCEPROP 2 LAST PATH I1
J 0
(-6150 3250);
DISPLAY 0.680851 (-6150 3250);
DISPLAY INVISIBLE (-6150 3250);
FORCEADD UNIVERSAL_POWER..1
(-4225 3975);
FORCEPROP 3 LASTPIN (-4225 3925) SIG_NAME P3V3_OCP_V3_2\g
J 0
(-4215 3935);
DISPLAY 0.659574 (-4215 3935);
PAINT MONO (-4215 3935);
DISPLAY INVISIBLE (-4215 3935);
FORCEPROP 1 LAST HDL_POWER P3V3_OCP_V3_2
J 1
(-4225 4025);
DISPLAY 0.872340 (-4225 4025);
PAINT GREEN (-4225 4025);
FORCEPROP 2 LAST CDS_LIB pure_quanta_power
J 0
(-4225 3975);
DISPLAY INVISIBLE (-4225 3975);
FORCEPROP 1 LAST PATH I10
J 0
(-4175 4000);
DISPLAY 0.872340 (-4175 4000);
PAINT AQUA (-4175 4000);
DISPLAY INVISIBLE (-4175 4000);
FORCEADD OFFPAGE..6
(-6175 5000);
FORCEPROP 2 LAST $XR1 151 
J 0
(-6575 5000);
DISPLAY 0.638298 (-6575 5000);
PAINT MONO (-6575 5000);
FORCEPROP 2 LAST $XR0 150 
J 0
(-6455 5000);
DISPLAY 0.638298 (-6455 5000);
PAINT MONO (-6455 5000);
FORCEPROP 2 LAST CDS_LIB standard
J 0
(-6175 5000);
DISPLAY INVISIBLE (-6175 5000);
FORCEPROP 1 LAST OFFPAGE TRUE
J 0
(-5850 4875);
DISPLAY 0.872340 (-5850 4875);
DISPLAY INVISIBLE (-5850 4875);
FORCEPROP 1 LAST COMMENT_BODY TRUE
J 0
(-6075 4925);
DISPLAY 0.872340 (-6075 4925);
PAINT GREEN (-6075 4925);
DISPLAY INVISIBLE (-6075 4925);
FORCEPROP 2 LAST PATH I11
J 0
(-6125 5075);
DISPLAY 0.680851 (-6125 5075);
DISPLAY INVISIBLE (-6125 5075);
FORCEADD OFFPAGE..1
(-6175 5100);
FORCEPROP 2 LAST $XR1 151 
J 0
(-6547 5100);
DISPLAY 0.638298 (-6547 5100);
PAINT MONO (-6547 5100);
FORCEPROP 2 LAST $XR0 150 
J 0
(-6427 5100);
DISPLAY 0.638298 (-6427 5100);
PAINT MONO (-6427 5100);
FORCEPROP 2 LAST CDS_LIB standard
J 0
(-6175 5100);
DISPLAY INVISIBLE (-6175 5100);
FORCEPROP 1 LAST OFFPAGE TRUE
J 0
(-5850 4975);
DISPLAY 0.872340 (-5850 4975);
PAINT GREEN (-5850 4975);
DISPLAY INVISIBLE (-5850 4975);
FORCEPROP 1 LAST COMMENT_BODY TRUE
J 0
(-6050 5000);
DISPLAY 0.872340 (-6050 5000);
PAINT GREEN (-6050 5000);
DISPLAY INVISIBLE (-6050 5000);
FORCEPROP 2 LAST PATH I12
J 0
(-6125 5175);
DISPLAY 0.680851 (-6125 5175);
DISPLAY INVISIBLE (-6125 5175);
FORCEADD UNIVERSAL_GND..1
(-5275 4625);
FORCEPROP 3 LASTPIN (-5275 4675) SIG_NAME GND\g
J 0
(-5265 4685);
DISPLAY 0.659574 (-5265 4685);
PAINT MONO (-5265 4685);
DISPLAY INVISIBLE (-5265 4685);
FORCEPROP 2 LAST CDS_LIB pure_quanta_power
J 0
(-5275 4625);
DISPLAY INVISIBLE (-5275 4625);
FORCEPROP 1 LAST HDL_POWER GND
J 1
(-5250 4550);
DISPLAY 0.872340 (-5250 4550);
PAINT GREEN (-5250 4550);
DISPLAY INVISIBLE (-5250 4550);
FORCEPROP 1 LAST PATH I13
J 0
(-5200 4625);
DISPLAY 0.872340 (-5200 4625);
PAINT AQUA (-5200 4625);
DISPLAY INVISIBLE (-5200 4625);
FORCEADD PCA9617ADP..1
(-4750 5050);
FORCEPROP 1 LAST LOCATION U236
J 0
(-5024 5460);
DISPLAY 0.723404 (-5024 5460);
PAINT GREEN (-5024 5460);
FORCEPROP 0 LAST $SEC 1
J 0
(-5000 5600);
DISPLAY 0.680851 (-5000 5600);
PAINT MONO (-5000 5600);
DISPLAY INVISIBLE (-5000 5600);
FORCEPROP 0 LAST CDS_SEC 1
J 0
(-5000 5600);
DISPLAY 1.021277 (-5000 5600);
DISPLAY INVISIBLE (-5000 5600);
FORCEPROP 0 LASTPIN (-4325 4850) $PN 5
J 0
(-4315 4860);
DISPLAY 0.680851 (-4315 4860);
PAINT MONO (-4315 4860);
FORCEPROP 0 LASTPIN (-5175 4850) $PN 4
J 2
(-5185 4860);
DISPLAY 0.680851 (-5185 4860);
PAINT MONO (-5185 4860);
FORCEPROP 0 LASTPIN (-5175 5100) $PN 2
J 2
(-5185 5110);
DISPLAY 0.680851 (-5185 5110);
PAINT MONO (-5185 5110);
FORCEPROP 0 LASTPIN (-4325 5100) $PN 7
J 0
(-4315 5110);
DISPLAY 0.680851 (-4315 5110);
PAINT MONO (-4315 5110);
FORCEPROP 0 LASTPIN (-5175 5000) $PN 3
J 2
(-5185 5010);
DISPLAY 0.680851 (-5185 5010);
PAINT MONO (-5185 5010);
FORCEPROP 0 LASTPIN (-4325 5000) $PN 6
J 0
(-4315 5010);
DISPLAY 0.680851 (-4315 5010);
PAINT MONO (-4315 5010);
FORCEPROP 0 LASTPIN (-5175 5250) $PN 1
J 2
(-5185 5260);
DISPLAY 0.680851 (-5185 5260);
PAINT MONO (-5185 5260);
FORCEPROP 0 LASTPIN (-4325 5250) $PN 8
J 0
(-4315 5260);
DISPLAY 0.680851 (-4315 5260);
PAINT MONO (-4315 5260);
FORCEPROP 2 LAST PART_TYPE SMLF
J 0
(-5000 5550);
DISPLAY 1.021277 (-5000 5550);
FORCEPROP 2 LAST VALUE PCA9617ADP
J 0
(-5000 5500);
DISPLAY 1.021277 (-5000 5500);
FORCEPROP 1 LAST MATERIAL IC
J 0
(-5024 5355);
DISPLAY 0.723404 (-5024 5355);
PAINT GREEN (-5024 5355);
FORCEPROP 1 LAST NEEDS_NO_SIZE TRUE
J 0
(-4475 4750);
DISPLAY 0.468085 (-4475 4750);
PAINT GREEN (-4475 4750);
DISPLAY INVISIBLE (-4475 4750);
FORCEPROP 1 LAST CDS_LMAN_SYM_OUTLINE -275,300,275,-300
J 0
(-4750 5050);
DISPLAY 0.468085 (-4750 5050);
PAINT GREEN (-4750 5050);
DISPLAY INVISIBLE (-4750 5050);
FORCEPROP 2 LAST CDS_LIB pure_quanta
J 0
(-4750 5050);
DISPLAY INVISIBLE (-4750 5050);
FORCEPROP 1 LAST PATH I14
J 0
(-4750 5050);
DISPLAY 0.723404 (-4750 5050);
PAINT GREEN (-4750 5050);
DISPLAY INVISIBLE (-4750 5050);
FORCEPROP 1 LAST PART_NUMBER AL009617K02
J 0
(-5024 5410);
DISPLAY 0.723404 (-5024 5410);
PAINT GREEN (-5024 5410);
DISPLAY INVISIBLE (-5024 5410);
FORCEADD Q_CAP..1
(-5675 5500);
FORCEPROP 1 LAST LOCATION C1860
J 0
(-5625 5600);
DISPLAY 0.978723 (-5625 5600);
FORCEPROP 2 LAST $SEC 1
J 0
(-5625 5700);
DISPLAY 0.680851 (-5625 5700);
PAINT MONO (-5625 5700);
DISPLAY INVISIBLE (-5625 5700);
FORCEPROP 2 LAST CDS_SEC 1
J 0
(-5625 5700);
DISPLAY 1.021277 (-5625 5700);
DISPLAY INVISIBLE (-5625 5700);
FORCEPROP 1 LASTPIN (-5675 5600) $PN 1
J 0
(-5665 5580);
DISPLAY 0.787234 (-5665 5580);
FORCEPROP 1 LASTPIN (-5675 5400) $PN 2
J 0
(-5665 5380);
DISPLAY 0.787234 (-5665 5380);
FORCEPROP 1 LAST VALUE 0.1UF
J 0
(-5625 5550);
DISPLAY 0.510638 (-5625 5550);
FORCEPROP 1 LAST TOLERANCE 10%
J 0
(-5625 5450);
DISPLAY 0.510638 (-5625 5450);
FORCEPROP 1 LAST MATERIAL X7R
J 0
(-5625 5400);
DISPLAY 0.510638 (-5625 5400);
FORCEPROP 1 LAST VOLTAGE 25V
J 0
(-5625 5500);
DISPLAY 0.510638 (-5625 5500);
FORCEPROP 1 LAST PACK_TYPE 0402
J 0
(-5625 5300);
DISPLAY 0.510638 (-5625 5300);
FORCEPROP 2 LAST CDS_LIB pure_quanta
J 0
(-5675 5500);
PAINT MONO (-5675 5500);
DISPLAY INVISIBLE (-5675 5500);
FORCEPROP 1 LAST PATH I15
J 0
(-5625 5650);
DISPLAY 0.978723 (-5625 5650);
PAINT WHITE (-5625 5650);
DISPLAY INVISIBLE (-5625 5650);
FORCEPROP 1 LAST PART_NUMBER CH4104K1B00
J 0
(-5625 5350);
DISPLAY 0.510638 (-5625 5350);
DISPLAY INVISIBLE (-5625 5350);
FORCEADD UNIVERSAL_GND..1
(-5675 5275);
FORCEPROP 3 LASTPIN (-5675 5325) SIG_NAME GND\g
J 0
(-5665 5335);
DISPLAY 0.659574 (-5665 5335);
PAINT MONO (-5665 5335);
DISPLAY INVISIBLE (-5665 5335);
FORCEPROP 2 LAST CDS_LIB pure_quanta_power
J 0
(-5675 5275);
PAINT MONO (-5675 5275);
DISPLAY INVISIBLE (-5675 5275);
FORCEPROP 1 LAST HDL_POWER GND
J 1
(-5650 5200);
DISPLAY 0.872340 (-5650 5200);
PAINT GREEN (-5650 5200);
DISPLAY INVISIBLE (-5650 5200);
FORCEPROP 1 LAST PATH I16
J 0
(-5600 5275);
DISPLAY 0.872340 (-5600 5275);
PAINT AQUA (-5600 5275);
DISPLAY INVISIBLE (-5600 5275);
FORCEADD UNIVERSAL_POWER..1
(-5325 5800);
FORCEPROP 3 LASTPIN (-5325 5750) SIG_NAME P3V3_AUX\g
J 0
(-5315 5760);
DISPLAY 0.659574 (-5315 5760);
PAINT MONO (-5315 5760);
DISPLAY INVISIBLE (-5315 5760);
FORCEPROP 1 LAST HDL_POWER P3V3_AUX
J 1
(-5325 5850);
DISPLAY 0.872340 (-5325 5850);
PAINT GREEN (-5325 5850);
FORCEPROP 2 LAST CDS_LIB pure_quanta_power
J 0
(-5325 5800);
PAINT MONO (-5325 5800);
DISPLAY INVISIBLE (-5325 5800);
FORCEPROP 1 LAST PATH I17
J 0
(-5275 5825);
DISPLAY 0.872340 (-5275 5825);
PAINT AQUA (-5275 5825);
DISPLAY INVISIBLE (-5275 5825);
FORCEADD UNIVERSAL_POWER..1
(-4200 5800);
FORCEPROP 3 LASTPIN (-4200 5750) SIG_NAME P3V3_OCP_SFF\g
J 0
(-4190 5760);
DISPLAY 0.659574 (-4190 5760);
PAINT MONO (-4190 5760);
DISPLAY INVISIBLE (-4190 5760);
FORCEPROP 1 LAST HDL_POWER P3V3_OCP_SFF
J 1
(-4200 5850);
DISPLAY 0.872340 (-4200 5850);
PAINT GREEN (-4200 5850);
FORCEPROP 2 LAST CDS_LIB pure_quanta_power
J 0
(-4200 5800);
DISPLAY INVISIBLE (-4200 5800);
FORCEPROP 1 LAST PATH I18
J 0
(-4150 5825);
DISPLAY 0.872340 (-4150 5825);
PAINT AQUA (-4150 5825);
DISPLAY INVISIBLE (-4150 5825);
FORCEADD Q_CAP..1
(-4000 5500);
FORCEPROP 1 LAST LOCATION C1862
J 0
(-3950 5600);
DISPLAY 0.978723 (-3950 5600);
FORCEPROP 0 LAST $SEC 1
J 0
(-3950 5650);
DISPLAY 0.680851 (-3950 5650);
PAINT MONO (-3950 5650);
DISPLAY INVISIBLE (-3950 5650);
FORCEPROP 0 LAST CDS_SEC 1
J 0
(-3950 5650);
DISPLAY 1.021277 (-3950 5650);
DISPLAY INVISIBLE (-3950 5650);
FORCEPROP 1 LASTPIN (-4000 5600) $PN 1
J 0
(-3990 5580);
DISPLAY 0.787234 (-3990 5580);
PAINT MONO (-3990 5580);
FORCEPROP 1 LASTPIN (-4000 5400) $PN 2
J 0
(-3990 5380);
DISPLAY 0.787234 (-3990 5380);
PAINT MONO (-3990 5380);
FORCEPROP 1 LAST TOLERANCE 10%
J 0
(-3950 5450);
DISPLAY 0.510638 (-3950 5450);
FORCEPROP 1 LAST VALUE 0.1UF
J 0
(-3950 5550);
DISPLAY 0.510638 (-3950 5550);
FORCEPROP 1 LAST VOLTAGE 25V
J 0
(-3950 5500);
DISPLAY 0.510638 (-3950 5500);
FORCEPROP 1 LAST PACK_TYPE 0402
J 0
(-3950 5300);
DISPLAY 0.510638 (-3950 5300);
FORCEPROP 1 LAST MATERIAL X7R
J 0
(-3950 5400);
DISPLAY 0.510638 (-3950 5400);
FORCEPROP 2 LAST CDS_LIB pure_quanta
J 0
(-4000 5500);
DISPLAY INVISIBLE (-4000 5500);
FORCEPROP 1 LAST PATH I19
J 0
(-3950 5650);
DISPLAY 0.978723 (-3950 5650);
PAINT WHITE (-3950 5650);
DISPLAY INVISIBLE (-3950 5650);
FORCEPROP 1 LAST PART_NUMBER CH4104K1B00
J 0
(-3950 5350);
DISPLAY 0.510638 (-3950 5350);
DISPLAY INVISIBLE (-3950 5350);
FORCEADD OFFPAGE..1
(-6200 3275);
FORCEPROP 2 LAST $XR1 151 
J 0
(-6572 3275);
DISPLAY 0.638298 (-6572 3275);
PAINT MONO (-6572 3275);
FORCEPROP 2 LAST $XR0 150 
J 0
(-6452 3275);
DISPLAY 0.638298 (-6452 3275);
PAINT MONO (-6452 3275);
FORCEPROP 2 LAST CDS_LIB standard
J 0
(-6200 3275);
DISPLAY INVISIBLE (-6200 3275);
FORCEPROP 1 LAST OFFPAGE TRUE
J 0
(-5875 3150);
DISPLAY 0.872340 (-5875 3150);
PAINT GREEN (-5875 3150);
DISPLAY INVISIBLE (-5875 3150);
FORCEPROP 1 LAST COMMENT_BODY TRUE
J 0
(-6075 3175);
DISPLAY 0.872340 (-6075 3175);
PAINT GREEN (-6075 3175);
DISPLAY INVISIBLE (-6075 3175);
FORCEPROP 2 LAST PATH I2
J 0
(-6150 3350);
DISPLAY 0.680851 (-6150 3350);
DISPLAY INVISIBLE (-6150 3350);
FORCEADD UNIVERSAL_GND..1
(-4000 5300);
FORCEPROP 3 LASTPIN (-4000 5350) SIG_NAME GND\g
J 0
(-3990 5360);
DISPLAY 0.659574 (-3990 5360);
PAINT MONO (-3990 5360);
DISPLAY INVISIBLE (-3990 5360);
FORCEPROP 2 LAST CDS_LIB pure_quanta_power
J 0
(-4000 5300);
DISPLAY INVISIBLE (-4000 5300);
FORCEPROP 1 LAST HDL_POWER GND
J 1
(-3975 5225);
DISPLAY 0.872340 (-3975 5225);
PAINT GREEN (-3975 5225);
DISPLAY INVISIBLE (-3975 5225);
FORCEPROP 1 LAST PATH I20
J 0
(-3925 5300);
DISPLAY 0.872340 (-3925 5300);
PAINT AQUA (-3925 5300);
DISPLAY INVISIBLE (-3925 5300);
FORCEADD UNIVERSAL_POWER..1
(-3200 3950);
FORCEPROP 3 LASTPIN (-3200 3900) SIG_NAME P3V3_OCP_V3_2\g
J 0
(-3190 3910);
DISPLAY 0.659574 (-3190 3910);
PAINT MONO (-3190 3910);
DISPLAY INVISIBLE (-3190 3910);
FORCEPROP 1 LAST HDL_POWER P3V3_OCP_V3_2
J 1
(-3200 4000);
DISPLAY 0.872340 (-3200 4000);
PAINT GREEN (-3200 4000);
FORCEPROP 2 LAST CDS_LIB pure_quanta_power
J 0
(-3200 3950);
DISPLAY INVISIBLE (-3200 3950);
FORCEPROP 1 LAST PATH I22
J 0
(-3150 3975);
DISPLAY 0.872340 (-3150 3975);
PAINT AQUA (-3150 3975);
DISPLAY INVISIBLE (-3150 3975);
FORCEADD Q_RES..2
(-2950 3625);
FORCEPROP 1 LAST LOCATION R3520
J 0
(-2905 3750);
DISPLAY 0.978723 (-2905 3750);
FORCEPROP 0 LAST $SEC 1
J 0
(-2900 3800);
DISPLAY 0.680851 (-2900 3800);
PAINT MONO (-2900 3800);
DISPLAY INVISIBLE (-2900 3800);
FORCEPROP 0 LAST CDS_SEC 1
J 0
(-2900 3800);
DISPLAY 1.021277 (-2900 3800);
DISPLAY INVISIBLE (-2900 3800);
FORCEPROP 1 LASTPIN (-2950 3725) $PN 1
J 0
(-2945 3687);
DISPLAY 0.787234 (-2945 3687);
PAINT MONO (-2945 3687);
FORCEPROP 1 LASTPIN (-2950 3525) $PN 2
J 0
(-2945 3535);
DISPLAY 0.787234 (-2945 3535);
PAINT MONO (-2945 3535);
FORCEPROP 1 LAST PACK_TYPE 0402LF
J 0
(-2925 3500);
DISPLAY 0.638298 (-2925 3500);
FORCEPROP 1 LAST MATERIAL CHIP
J 0
(-2910 3550);
DISPLAY 0.638298 (-2910 3550);
FORCEPROP 1 LAST WATTAGE 1/16W
J 0
(-2910 3600);
DISPLAY 0.638298 (-2910 3600);
FORCEPROP 1 LAST TOLERANCE 5%
J 0
(-2905 3650);
DISPLAY 0.638298 (-2905 3650);
FORCEPROP 1 LAST VALUE 4.7K
J 0
(-2905 3700);
DISPLAY 0.638298 (-2905 3700);
FORCEPROP 2 LAST CDS_LIB pure_quanta
J 0
(-2950 3625);
DISPLAY INVISIBLE (-2950 3625);
FORCEPROP 1 LAST PATH I23
J 0
(-2900 3800);
DISPLAY 0.978723 (-2900 3800);
PAINT WHITE (-2900 3800);
DISPLAY INVISIBLE (-2900 3800);
FORCEPROP 1 LAST PART_NUMBER CS24702JB10
J 0
(-2910 3450);
DISPLAY 0.638298 (-2910 3450);
DISPLAY INVISIBLE (-2910 3450);
FORCEADD OFFPAGE..3
(-2375 3175);
FORCEPROP 2 LAST $XR0 137 
J 0
(-2161 3175);
DISPLAY 0.638298 (-2161 3175);
PAINT MONO (-2161 3175);
FORCEPROP 2 LAST CDS_LIB standard
J 0
(-2375 3175);
DISPLAY INVISIBLE (-2375 3175);
FORCEPROP 1 LAST OFFPAGE TRUE
J 0
(-2050 3050);
DISPLAY 0.872340 (-2050 3050);
PAINT GREEN (-2050 3050);
DISPLAY INVISIBLE (-2050 3050);
FORCEPROP 1 LAST COMMENT_BODY TRUE
J 0
(-2425 3075);
DISPLAY 0.872340 (-2425 3075);
PAINT GREEN (-2425 3075);
DISPLAY INVISIBLE (-2425 3075);
FORCEPROP 2 LAST PATH I24
J 0
(-2150 3225);
DISPLAY 0.680851 (-2150 3225);
DISPLAY INVISIBLE (-2150 3225);
FORCEADD OFFPAGE..2
(-2375 3275);
FORCEPROP 2 LAST $XR0 137 
J 0
(-2186 3275);
DISPLAY 0.638298 (-2186 3275);
PAINT MONO (-2186 3275);
FORCEPROP 2 LAST CDS_LIB standard
J 0
(-2375 3275);
DISPLAY INVISIBLE (-2375 3275);
FORCEPROP 1 LAST OFFPAGE TRUE
J 0
(-2050 3150);
DISPLAY 0.872340 (-2050 3150);
PAINT GREEN (-2050 3150);
DISPLAY INVISIBLE (-2050 3150);
FORCEPROP 1 LAST COMMENT_BODY TRUE
J 0
(-2420 3180);
DISPLAY 0.872340 (-2420 3180);
PAINT GREEN (-2420 3180);
DISPLAY INVISIBLE (-2420 3180);
FORCEPROP 2 LAST PATH I25
J 0
(-2175 3325);
DISPLAY 0.680851 (-2175 3325);
DISPLAY INVISIBLE (-2175 3325);
FORCEADD Q_RES..2
(-3025 5450);
FORCEPROP 1 LAST LOCATION R3500
J 0
(-2980 5575);
DISPLAY 0.638298 (-2980 5575);
FORCEPROP 2 LAST $SEC 1
J 0
(-2975 5675);
DISPLAY 0.680851 (-2975 5675);
PAINT MONO (-2975 5675);
DISPLAY INVISIBLE (-2975 5675);
FORCEPROP 2 LAST CDS_SEC 1
J 0
(-2975 5675);
DISPLAY 1.021277 (-2975 5675);
DISPLAY INVISIBLE (-2975 5675);
FORCEPROP 1 LASTPIN (-3025 5550) $PN 1
J 0
(-3020 5512);
DISPLAY 0.787234 (-3020 5512);
FORCEPROP 1 LASTPIN (-3025 5350) $PN 2
J 0
(-3020 5360);
DISPLAY 0.787234 (-3020 5360);
FORCEPROP 1 LAST PACK_TYPE 0402LF
J 0
(-2985 5325);
DISPLAY 0.638298 (-2985 5325);
FORCEPROP 1 LAST MATERIAL CHIP
J 0
(-2985 5375);
DISPLAY 0.638298 (-2985 5375);
FORCEPROP 1 LAST VALUE 4.7K
J 0
(-2980 5525);
DISPLAY 0.638298 (-2980 5525);
FORCEPROP 1 LAST TOLERANCE 5%
J 0
(-2980 5475);
DISPLAY 0.638298 (-2980 5475);
FORCEPROP 1 LAST WATTAGE 1/16W
J 0
(-2985 5425);
DISPLAY 0.638298 (-2985 5425);
FORCEPROP 2 LAST CDS_LIB pure_quanta
J 0
(-3025 5450);
PAINT MONO (-3025 5450);
DISPLAY INVISIBLE (-3025 5450);
FORCEPROP 1 LAST PATH I27
J 0
(-2975 5625);
DISPLAY 0.978723 (-2975 5625);
PAINT WHITE (-2975 5625);
DISPLAY INVISIBLE (-2975 5625);
FORCEPROP 1 LAST PART_NUMBER CS24702JB10
J 0
(-2985 5275);
DISPLAY 0.638298 (-2985 5275);
DISPLAY INVISIBLE (-2985 5275);
FORCEADD UNIVERSAL_POWER..1
(-3025 5775);
FORCEPROP 3 LASTPIN (-3025 5725) SIG_NAME P3V3_OCP_SFF\g
J 0
(-3015 5735);
DISPLAY 0.659574 (-3015 5735);
PAINT MONO (-3015 5735);
DISPLAY INVISIBLE (-3015 5735);
FORCEPROP 1 LAST HDL_POWER P3V3_OCP_SFF
J 1
(-3025 5825);
DISPLAY 0.872340 (-3025 5825);
PAINT GREEN (-3025 5825);
FORCEPROP 2 LAST CDS_LIB pure_quanta_power
J 0
(-3025 5775);
PAINT MONO (-3025 5775);
DISPLAY INVISIBLE (-3025 5775);
FORCEPROP 1 LAST PATH I28
J 0
(-2975 5800);
DISPLAY 0.872340 (-2975 5800);
PAINT AQUA (-2975 5800);
DISPLAY INVISIBLE (-2975 5800);
FORCEADD OFFPAGE..1
R 2
(-1975 4850);
FORCEPROP 2 LAST $XR3 135 
J 0
(-1489 4850);
DISPLAY 0.638298 (-1489 4850);
PAINT MONO (-1489 4850);
FORCEPROP 2 LAST $XR2 134 
J 0
(-1609 4850);
DISPLAY 0.638298 (-1609 4850);
PAINT MONO (-1609 4850);
FORCEPROP 2 LAST $XR1 83 
J 0
(-1699 4850);
DISPLAY 0.638298 (-1699 4850);
PAINT MONO (-1699 4850);
FORCEPROP 2 LAST $XR0 80 
J 0
(-1789 4850);
DISPLAY 0.638298 (-1789 4850);
PAINT MONO (-1789 4850);
FORCEPROP 2 LAST CDS_LIB standard
J 2
(-1975 4850);
DISPLAY INVISIBLE (-1975 4850);
FORCEPROP 1 LAST OFFPAGE TRUE
J 2
(-2300 4725);
DISPLAY 0.872340 (-2300 4725);
PAINT GREEN (-2300 4725);
DISPLAY INVISIBLE (-2300 4725);
FORCEPROP 1 LAST COMMENT_BODY TRUE
J 2
(-2100 4750);
DISPLAY 0.872340 (-2100 4750);
PAINT GREEN (-2100 4750);
DISPLAY INVISIBLE (-2100 4750);
FORCEPROP 2 LAST PATH I29
J 0
(-1525 4900);
DISPLAY 0.680851 (-1525 4900);
DISPLAY INVISIBLE (-1525 4900);
FORCEADD UNIVERSAL_GND..1
(-5300 2800);
FORCEPROP 3 LASTPIN (-5300 2850) SIG_NAME GND\g
J 0
(-5290 2860);
DISPLAY 0.659574 (-5290 2860);
PAINT MONO (-5290 2860);
DISPLAY INVISIBLE (-5290 2860);
FORCEPROP 2 LAST CDS_LIB pure_quanta_power
J 0
(-5300 2800);
DISPLAY INVISIBLE (-5300 2800);
FORCEPROP 1 LAST HDL_POWER GND
J 1
(-5275 2725);
DISPLAY 0.872340 (-5275 2725);
PAINT GREEN (-5275 2725);
DISPLAY INVISIBLE (-5275 2725);
FORCEPROP 1 LAST PATH I3
J 0
(-5225 2800);
DISPLAY 0.872340 (-5225 2800);
PAINT AQUA (-5225 2800);
DISPLAY INVISIBLE (-5225 2800);
FORCEADD OFFPAGE..3
(-2250 5000);
FORCEPROP 2 LAST $XR0 131 
J 0
(-2036 5000);
DISPLAY 0.638298 (-2036 5000);
PAINT MONO (-2036 5000);
FORCEPROP 2 LAST CDS_LIB standard
J 0
(-2250 5000);
DISPLAY INVISIBLE (-2250 5000);
FORCEPROP 1 LAST OFFPAGE TRUE
J 0
(-1925 4875);
DISPLAY 0.872340 (-1925 4875);
PAINT GREEN (-1925 4875);
DISPLAY INVISIBLE (-1925 4875);
FORCEPROP 1 LAST COMMENT_BODY TRUE
J 0
(-2300 4900);
DISPLAY 0.872340 (-2300 4900);
PAINT GREEN (-2300 4900);
DISPLAY INVISIBLE (-2300 4900);
FORCEPROP 2 LAST PATH I30
J 0
(-2050 5075);
DISPLAY 0.680851 (-2050 5075);
DISPLAY INVISIBLE (-2050 5075);
FORCEADD Q_RES..2
(-2775 5450);
FORCEPROP 1 LAST LOCATION R3501
J 0
(-2730 5575);
DISPLAY 0.638298 (-2730 5575);
FORCEPROP 2 LAST $SEC 1
J 0
(-2725 5675);
DISPLAY 0.680851 (-2725 5675);
PAINT MONO (-2725 5675);
DISPLAY INVISIBLE (-2725 5675);
FORCEPROP 2 LAST CDS_SEC 1
J 0
(-2725 5675);
DISPLAY 1.021277 (-2725 5675);
DISPLAY INVISIBLE (-2725 5675);
FORCEPROP 1 LASTPIN (-2775 5550) $PN 1
J 0
(-2770 5512);
DISPLAY 0.787234 (-2770 5512);
FORCEPROP 1 LASTPIN (-2775 5350) $PN 2
J 0
(-2770 5360);
DISPLAY 0.787234 (-2770 5360);
FORCEPROP 1 LAST MATERIAL CHIP
J 0
(-2735 5375);
DISPLAY 0.638298 (-2735 5375);
FORCEPROP 1 LAST PACK_TYPE 0402LF
J 0
(-2750 5325);
DISPLAY 0.638298 (-2750 5325);
FORCEPROP 1 LAST WATTAGE 1/16W
J 0
(-2735 5425);
DISPLAY 0.638298 (-2735 5425);
FORCEPROP 1 LAST TOLERANCE 5%
J 0
(-2730 5475);
DISPLAY 0.638298 (-2730 5475);
FORCEPROP 1 LAST VALUE 4.7K
J 0
(-2730 5525);
DISPLAY 0.638298 (-2730 5525);
FORCEPROP 2 LAST CDS_LIB pure_quanta
J 0
(-2775 5450);
PAINT MONO (-2775 5450);
DISPLAY INVISIBLE (-2775 5450);
FORCEPROP 1 LAST PATH I31
J 0
(-2725 5625);
DISPLAY 0.978723 (-2725 5625);
PAINT WHITE (-2725 5625);
DISPLAY INVISIBLE (-2725 5625);
FORCEPROP 1 LAST PART_NUMBER CS24702JB10
J 0
(-2735 5275);
DISPLAY 0.638298 (-2735 5275);
DISPLAY INVISIBLE (-2735 5275);
FORCEADD OFFPAGE..2
(-2250 5100);
FORCEPROP 2 LAST $XR0 131 
J 0
(-2061 5100);
DISPLAY 0.638298 (-2061 5100);
PAINT MONO (-2061 5100);
FORCEPROP 2 LAST CDS_LIB standard
J 0
(-2250 5100);
DISPLAY INVISIBLE (-2250 5100);
FORCEPROP 1 LAST OFFPAGE TRUE
J 0
(-1925 4975);
DISPLAY 0.872340 (-1925 4975);
PAINT GREEN (-1925 4975);
DISPLAY INVISIBLE (-1925 4975);
FORCEPROP 1 LAST COMMENT_BODY TRUE
J 0
(-2295 5005);
DISPLAY 0.872340 (-2295 5005);
PAINT GREEN (-2295 5005);
DISPLAY INVISIBLE (-2295 5005);
FORCEPROP 2 LAST PATH I32
J 0
(-2075 5175);
DISPLAY 0.680851 (-2075 5175);
DISPLAY INVISIBLE (-2075 5175);
FORCEADD OFFPAGE..1
R 2
(-2375 3025);
FORCEPROP 2 LAST $XR3 141 
J 0
(-1889 3025);
DISPLAY 0.638298 (-1889 3025);
PAINT MONO (-1889 3025);
FORCEPROP 2 LAST $XR2 140 
J 0
(-2009 3025);
DISPLAY 0.638298 (-2009 3025);
PAINT MONO (-2009 3025);
FORCEPROP 2 LAST $XR1 83 
J 0
(-2099 3025);
DISPLAY 0.638298 (-2099 3025);
PAINT MONO (-2099 3025);
FORCEPROP 2 LAST $XR0 81 
J 0
(-2189 3025);
DISPLAY 0.638298 (-2189 3025);
PAINT MONO (-2189 3025);
FORCEPROP 2 LAST CDS_LIB standard
J 2
(-2375 3025);
DISPLAY INVISIBLE (-2375 3025);
FORCEPROP 1 LAST OFFPAGE TRUE
J 2
(-2700 2900);
DISPLAY 0.872340 (-2700 2900);
PAINT GREEN (-2700 2900);
DISPLAY INVISIBLE (-2700 2900);
FORCEPROP 1 LAST COMMENT_BODY TRUE
J 2
(-2500 2925);
DISPLAY 0.872340 (-2500 2925);
PAINT GREEN (-2500 2925);
DISPLAY INVISIBLE (-2500 2925);
FORCEPROP 2 LAST PATH I33
J 0
(-1925 3075);
DISPLAY 0.680851 (-1925 3075);
DISPLAY INVISIBLE (-1925 3075);
FORCEADD Q_RES..2
(-3200 3625);
FORCEPROP 1 LAST LOCATION R3519
J 0
(-3155 3750);
DISPLAY 0.978723 (-3155 3750);
FORCEPROP 0 LAST $SEC 1
J 0
(-3150 3800);
DISPLAY 0.680851 (-3150 3800);
PAINT MONO (-3150 3800);
DISPLAY INVISIBLE (-3150 3800);
FORCEPROP 0 LAST CDS_SEC 1
J 0
(-3150 3800);
DISPLAY 1.021277 (-3150 3800);
DISPLAY INVISIBLE (-3150 3800);
FORCEPROP 1 LASTPIN (-3200 3725) $PN 1
J 0
(-3195 3687);
DISPLAY 0.787234 (-3195 3687);
PAINT MONO (-3195 3687);
FORCEPROP 1 LASTPIN (-3200 3525) $PN 2
J 0
(-3195 3535);
DISPLAY 0.787234 (-3195 3535);
PAINT MONO (-3195 3535);
FORCEPROP 1 LAST VALUE 4.7K
J 0
(-3155 3700);
DISPLAY 0.638298 (-3155 3700);
FORCEPROP 1 LAST TOLERANCE 5%
J 0
(-3155 3650);
DISPLAY 0.638298 (-3155 3650);
FORCEPROP 1 LAST WATTAGE 1/16W
J 0
(-3160 3600);
DISPLAY 0.638298 (-3160 3600);
FORCEPROP 1 LAST MATERIAL CHIP
J 0
(-3160 3550);
DISPLAY 0.638298 (-3160 3550);
FORCEPROP 1 LAST PACK_TYPE 0402LF
J 0
(-3160 3500);
DISPLAY 0.638298 (-3160 3500);
FORCEPROP 2 LAST CDS_LIB pure_quanta
J 0
(-3200 3625);
DISPLAY INVISIBLE (-3200 3625);
FORCEPROP 1 LAST PATH I34
J 0
(-3150 3800);
DISPLAY 0.978723 (-3150 3800);
PAINT WHITE (-3150 3800);
DISPLAY INVISIBLE (-3150 3800);
FORCEPROP 1 LAST PART_NUMBER CS24702JB10
J 0
(-3160 3450);
DISPLAY 0.638298 (-3160 3450);
DISPLAY INVISIBLE (-3160 3450);
FORCEADD Q_RES..1
(-3450 4850);
FORCEPROP 1 LAST LOCATION R3263
J 0
(-3700 4850);
DISPLAY 0.638298 (-3700 4850);
FORCEPROP 0 LAST $SEC 1
J 0
(-3325 4900);
DISPLAY 0.680851 (-3325 4900);
PAINT MONO (-3325 4900);
DISPLAY INVISIBLE (-3325 4900);
FORCEPROP 0 LAST CDS_SEC 1
J 0
(-3325 4900);
DISPLAY 0.680851 (-3325 4900);
DISPLAY INVISIBLE (-3325 4900);
FORCEPROP 1 LASTPIN (-3550 4850) $PN 1
J 0
(-3538 4862);
DISPLAY 0.787234 (-3538 4862);
PAINT MONO (-3538 4862);
FORCEPROP 1 LASTPIN (-3350 4850) $PN 2
J 0
(-3388 4862);
DISPLAY 0.787234 (-3388 4862);
PAINT MONO (-3388 4862);
FORCEPROP 1 LAST TOLERANCE 5%
J 0
(-3275 4850);
DISPLAY 0.510638 (-3275 4850);
FORCEPROP 1 LAST VALUE 0
J 2
(-3300 4850);
DISPLAY 0.510638 (-3300 4850);
FORCEPROP 1 LAST PACK_TYPE 0402LF
J 0
(-3325 4875);
DISPLAY 0.510638 (-3325 4875);
FORCEPROP 1 LAST MATERIAL EMPTY
J 0
(-3200 4850);
DISPLAY 0.510638 (-3200 4850);
PAINT RED (-3200 4850);
FORCEPROP 2 LAST CDS_LIB pure_quanta
J 0
(-3450 4850);
DISPLAY INVISIBLE (-3450 4850);
FORCEPROP 1 LAST WATTAGE 1/16W
J 2
(-3350 4775);
DISPLAY 0.319149 (-3350 4775);
DISPLAY INVISIBLE (-3350 4775);
FORCEPROP 1 LAST PATH I35
J 0
(-3500 5000);
DISPLAY 0.978723 (-3500 5000);
PAINT WHITE (-3500 5000);
DISPLAY INVISIBLE (-3500 5000);
FORCEPROP 1 LAST PART_NUMBER CS00002JB13
J 0
(-3525 4800);
DISPLAY 0.319149 (-3525 4800);
DISPLAY INVISIBLE (-3525 4800);
FORCEADD OFFPAGE..1
R 2
(-2000 4650);
FORCEPROP 2 LAST $XR2 136 
J 0
(-1574 4650);
DISPLAY 0.638298 (-1574 4650);
PAINT MONO (-1574 4650);
FORCEPROP 2 LAST $XR1 135 
J 0
(-1694 4650);
DISPLAY 0.638298 (-1694 4650);
PAINT MONO (-1694 4650);
FORCEPROP 2 LAST $XR0 134 
J 0
(-1814 4650);
DISPLAY 0.638298 (-1814 4650);
PAINT MONO (-1814 4650);
FORCEPROP 2 LAST CDS_LIB standard
J 0
(-2000 4650);
DISPLAY INVISIBLE (-2000 4650);
FORCEPROP 1 LAST OFFPAGE TRUE
J 2
(-2325 4525);
DISPLAY 0.872340 (-2325 4525);
PAINT GREEN (-2325 4525);
DISPLAY INVISIBLE (-2325 4525);
FORCEPROP 1 LAST COMMENT_BODY TRUE
J 2
(-2125 4550);
DISPLAY 0.872340 (-2125 4550);
PAINT GREEN (-2125 4550);
DISPLAY INVISIBLE (-2125 4550);
FORCEPROP 2 LAST PATH I37
J 0
(-1825 4725);
DISPLAY 0.680851 (-1825 4725);
DISPLAY INVISIBLE (-1825 4725);
FORCEADD Q_RES..1
(-3375 3025);
FORCEPROP 1 LAST LOCATION R3264
J 0
(-3600 3050);
DISPLAY 0.638298 (-3600 3050);
FORCEPROP 0 LAST $SEC 1
J 0
(-3425 3100);
DISPLAY 0.680851 (-3425 3100);
PAINT MONO (-3425 3100);
DISPLAY INVISIBLE (-3425 3100);
FORCEPROP 0 LAST CDS_SEC 1
J 0
(-3425 3100);
DISPLAY 0.680851 (-3425 3100);
DISPLAY INVISIBLE (-3425 3100);
FORCEPROP 1 LASTPIN (-3475 3025) $PN 1
J 0
(-3463 3037);
DISPLAY 0.787234 (-3463 3037);
PAINT MONO (-3463 3037);
FORCEPROP 1 LASTPIN (-3275 3025) $PN 2
J 0
(-3313 3037);
DISPLAY 0.787234 (-3313 3037);
PAINT MONO (-3313 3037);
FORCEPROP 1 LAST MATERIAL EMPTY
J 0
(-3425 2975);
DISPLAY 0.510638 (-3425 2975);
PAINT RED (-3425 2975);
FORCEPROP 1 LAST TOLERANCE 5%
J 0
(-3200 3025);
DISPLAY 0.510638 (-3200 3025);
FORCEPROP 1 LAST VALUE 0
J 2
(-3225 3025);
DISPLAY 0.510638 (-3225 3025);
FORCEPROP 1 LAST WATTAGE 1/16W
J 2
(-3275 2950);
DISPLAY 0.319149 (-3275 2950);
DISPLAY INVISIBLE (-3275 2950);
FORCEPROP 1 LAST PACK_TYPE 0402LF
J 0
(-3125 3025);
DISPLAY 0.510638 (-3125 3025);
DISPLAY INVISIBLE (-3125 3025);
FORCEPROP 2 LAST CDS_LIB pure_quanta
J 0
(-3375 3025);
DISPLAY INVISIBLE (-3375 3025);
FORCEPROP 1 LAST PATH I38
J 0
(-3425 3175);
DISPLAY 0.978723 (-3425 3175);
PAINT WHITE (-3425 3175);
DISPLAY INVISIBLE (-3425 3175);
FORCEPROP 1 LAST PART_NUMBER CS00002JB13
J 0
(-3450 2975);
DISPLAY 0.319149 (-3450 2975);
DISPLAY INVISIBLE (-3450 2975);
FORCEADD Q_CAP..1
(-5700 3675);
FORCEPROP 1 LAST LOCATION C1859
J 0
(-5650 3775);
DISPLAY 0.978723 (-5650 3775);
FORCEPROP 2 LAST $SEC 1
J 0
(-5650 3875);
DISPLAY 0.680851 (-5650 3875);
PAINT MONO (-5650 3875);
DISPLAY INVISIBLE (-5650 3875);
FORCEPROP 2 LAST CDS_SEC 1
J 0
(-5650 3875);
DISPLAY 1.021277 (-5650 3875);
DISPLAY INVISIBLE (-5650 3875);
FORCEPROP 1 LASTPIN (-5700 3775) $PN 1
J 0
(-5690 3755);
DISPLAY 0.787234 (-5690 3755);
FORCEPROP 1 LASTPIN (-5700 3575) $PN 2
J 0
(-5690 3555);
DISPLAY 0.787234 (-5690 3555);
FORCEPROP 1 LAST VALUE 0.1UF
J 0
(-5650 3725);
DISPLAY 0.510638 (-5650 3725);
FORCEPROP 1 LAST VOLTAGE 25V
J 0
(-5650 3675);
DISPLAY 0.510638 (-5650 3675);
FORCEPROP 1 LAST MATERIAL X7R
J 0
(-5650 3575);
DISPLAY 0.510638 (-5650 3575);
FORCEPROP 1 LAST PACK_TYPE 0402
J 0
(-5650 3475);
DISPLAY 0.510638 (-5650 3475);
FORCEPROP 1 LAST TOLERANCE 10%
J 0
(-5650 3625);
DISPLAY 0.510638 (-5650 3625);
FORCEPROP 2 LAST CDS_LIB pure_quanta
J 0
(-5700 3675);
PAINT MONO (-5700 3675);
DISPLAY INVISIBLE (-5700 3675);
FORCEPROP 1 LAST PATH I4
J 0
(-5650 3825);
DISPLAY 0.978723 (-5650 3825);
PAINT WHITE (-5650 3825);
DISPLAY INVISIBLE (-5650 3825);
FORCEPROP 1 LAST PART_NUMBER CH4104K1B00
J 0
(-5650 3525);
DISPLAY 0.510638 (-5650 3525);
DISPLAY INVISIBLE (-5650 3525);
FORCEADD OFFPAGE..1
R 2
(-1850 2850);
FORCEPROP 2 LAST $XR2 142 
J 0
(-1424 2850);
DISPLAY 0.638298 (-1424 2850);
PAINT MONO (-1424 2850);
FORCEPROP 2 LAST $XR1 141 
J 0
(-1544 2850);
DISPLAY 0.638298 (-1544 2850);
PAINT MONO (-1544 2850);
FORCEPROP 2 LAST $XR0 140 
J 0
(-1664 2850);
DISPLAY 0.638298 (-1664 2850);
PAINT MONO (-1664 2850);
FORCEPROP 2 LAST CDS_LIB standard
J 0
(-1850 2850);
DISPLAY INVISIBLE (-1850 2850);
FORCEPROP 1 LAST OFFPAGE TRUE
J 2
(-2175 2725);
DISPLAY 0.872340 (-2175 2725);
PAINT GREEN (-2175 2725);
DISPLAY INVISIBLE (-2175 2725);
FORCEPROP 1 LAST COMMENT_BODY TRUE
J 2
(-1975 2750);
DISPLAY 0.872340 (-1975 2750);
PAINT GREEN (-1975 2750);
DISPLAY INVISIBLE (-1975 2750);
FORCEPROP 2 LAST PATH I40
J 0
(-1675 2925);
DISPLAY 0.680851 (-1675 2925);
DISPLAY INVISIBLE (-1675 2925);
FORCEADD Q_RES..1
(-3450 4650);
FORCEPROP 1 LAST LOCATION R1135
J 0
(-3700 4650);
DISPLAY 0.638298 (-3700 4650);
FORCEPROP 0 LAST $SEC 1
J 0
(-3325 4700);
DISPLAY 0.680851 (-3325 4700);
PAINT MONO (-3325 4700);
DISPLAY INVISIBLE (-3325 4700);
FORCEPROP 0 LAST CDS_SEC 1
J 0
(-3325 4700);
DISPLAY 0.680851 (-3325 4700);
DISPLAY INVISIBLE (-3325 4700);
FORCEPROP 1 LASTPIN (-3550 4650) $PN 1
J 0
(-3538 4662);
DISPLAY 0.787234 (-3538 4662);
PAINT MONO (-3538 4662);
FORCEPROP 1 LASTPIN (-3350 4650) $PN 2
J 0
(-3388 4662);
DISPLAY 0.787234 (-3388 4662);
PAINT MONO (-3388 4662);
FORCEPROP 1 LAST PACK_TYPE 0402LF
J 0
(-3325 4675);
DISPLAY 0.510638 (-3325 4675);
FORCEPROP 1 LAST TOLERANCE 5%
J 0
(-3275 4650);
DISPLAY 0.510638 (-3275 4650);
FORCEPROP 1 LAST MATERIAL EMPTY
J 0
(-3200 4650);
DISPLAY 0.510638 (-3200 4650);
PAINT RED (-3200 4650);
FORCEPROP 1 LAST VALUE 0
J 2
(-3300 4650);
DISPLAY 0.510638 (-3300 4650);
FORCEPROP 2 LAST CDS_LIB pure_quanta
J 0
(-3450 4650);
DISPLAY INVISIBLE (-3450 4650);
FORCEPROP 1 LAST WATTAGE 1/16W
J 2
(-3350 4575);
DISPLAY 0.319149 (-3350 4575);
DISPLAY INVISIBLE (-3350 4575);
FORCEPROP 1 LAST PATH I41
J 0
(-3500 4800);
DISPLAY 0.978723 (-3500 4800);
PAINT WHITE (-3500 4800);
DISPLAY INVISIBLE (-3500 4800);
FORCEPROP 1 LAST PART_NUMBER CS00002JB13
J 0
(-3525 4600);
DISPLAY 0.319149 (-3525 4600);
DISPLAY INVISIBLE (-3525 4600);
FORCEADD OFFPAGE..1
R 2
(-2000 4475);
FORCEPROP 2 LAST $XR2 135 
J 0
(-1574 4475);
DISPLAY 0.638298 (-1574 4475);
PAINT MONO (-1574 4475);
FORCEPROP 2 LAST $XR1 134 
J 0
(-1694 4475);
DISPLAY 0.638298 (-1694 4475);
PAINT MONO (-1694 4475);
FORCEPROP 2 LAST $XR0 136 
J 0
(-1814 4475);
DISPLAY 0.638298 (-1814 4475);
PAINT MONO (-1814 4475);
FORCEPROP 2 LAST CDS_LIB standard
J 0
(-2000 4475);
DISPLAY INVISIBLE (-2000 4475);
FORCEPROP 1 LAST OFFPAGE TRUE
J 2
(-2325 4350);
DISPLAY 0.872340 (-2325 4350);
PAINT GREEN (-2325 4350);
DISPLAY INVISIBLE (-2325 4350);
FORCEPROP 1 LAST COMMENT_BODY TRUE
J 2
(-2125 4375);
DISPLAY 0.872340 (-2125 4375);
PAINT GREEN (-2125 4375);
DISPLAY INVISIBLE (-2125 4375);
FORCEPROP 2 LAST PATH I42
J 0
(-1825 4550);
DISPLAY 0.680851 (-1825 4550);
DISPLAY INVISIBLE (-1825 4550);
FORCEADD Q_RES..1
(-3450 4475);
FORCEPROP 1 LAST LOCATION R1500
J 0
(-3725 4500);
DISPLAY 0.787234 (-3725 4500);
FORCEPROP 0 LAST $SEC 1
J 0
(-3600 4550);
DISPLAY 0.680851 (-3600 4550);
PAINT MONO (-3600 4550);
DISPLAY INVISIBLE (-3600 4550);
FORCEPROP 0 LAST CDS_SEC 1
J 0
(-3600 4550);
DISPLAY 0.680851 (-3600 4550);
DISPLAY INVISIBLE (-3600 4550);
FORCEPROP 1 LASTPIN (-3550 4475) $PN 1
J 0
(-3538 4487);
DISPLAY 0.787234 (-3538 4487);
PAINT MONO (-3538 4487);
FORCEPROP 1 LASTPIN (-3350 4475) $PN 2
J 0
(-3388 4487);
DISPLAY 0.787234 (-3388 4487);
PAINT MONO (-3388 4487);
FORCEPROP 1 LAST TOLERANCE 5%
J 0
(-3275 4475);
DISPLAY 0.510638 (-3275 4475);
FORCEPROP 1 LAST MATERIAL CHIP
J 0
(-3225 4475);
DISPLAY 0.510638 (-3225 4475);
FORCEPROP 1 LAST VALUE 0
J 2
(-3300 4475);
DISPLAY 0.510638 (-3300 4475);
FORCEPROP 1 LAST PACK_TYPE 0402LF
J 0
(-3200 4475);
DISPLAY 0.510638 (-3200 4475);
DISPLAY INVISIBLE (-3200 4475);
FORCEPROP 1 LAST WATTAGE 1/16W
J 2
(-3350 4400);
DISPLAY 0.319149 (-3350 4400);
DISPLAY INVISIBLE (-3350 4400);
FORCEPROP 2 LAST CDS_LIB pure_quanta
J 0
(-3450 4475);
DISPLAY INVISIBLE (-3450 4475);
FORCEPROP 1 LAST PATH I43
J 0
(-3500 4625);
DISPLAY 0.978723 (-3500 4625);
PAINT WHITE (-3500 4625);
DISPLAY INVISIBLE (-3500 4625);
FORCEPROP 1 LAST PART_NUMBER CS00002JB13
J 0
(-3525 4425);
DISPLAY 0.319149 (-3525 4425);
DISPLAY INVISIBLE (-3525 4425);
FORCEADD Q_RES..1
(-3350 2600);
FORCEPROP 1 LAST LOCATION R1522
J 0
(-3575 2550);
DISPLAY 0.787234 (-3575 2550);
FORCEPROP 0 LAST $SEC 1
J 0
(-3500 2675);
DISPLAY 0.680851 (-3500 2675);
PAINT MONO (-3500 2675);
DISPLAY INVISIBLE (-3500 2675);
FORCEPROP 0 LAST CDS_SEC 1
J 0
(-3500 2675);
DISPLAY 0.680851 (-3500 2675);
DISPLAY INVISIBLE (-3500 2675);
FORCEPROP 1 LASTPIN (-3450 2600) $PN 1
J 0
(-3438 2612);
DISPLAY 0.787234 (-3438 2612);
PAINT MONO (-3438 2612);
FORCEPROP 1 LASTPIN (-3250 2600) $PN 2
J 0
(-3288 2612);
DISPLAY 0.787234 (-3288 2612);
PAINT MONO (-3288 2612);
FORCEPROP 1 LAST MATERIAL CHIP
J 0
(-3125 2600);
DISPLAY 0.510638 (-3125 2600);
FORCEPROP 1 LAST VALUE 0
J 2
(-3200 2600);
DISPLAY 0.510638 (-3200 2600);
FORCEPROP 1 LAST TOLERANCE 5%
J 0
(-3175 2600);
DISPLAY 0.510638 (-3175 2600);
FORCEPROP 2 LAST CDS_LIB pure_quanta
J 0
(-3350 2600);
DISPLAY INVISIBLE (-3350 2600);
FORCEPROP 1 LAST PACK_TYPE 0402LF
J 0
(-3100 2600);
DISPLAY 0.510638 (-3100 2600);
DISPLAY INVISIBLE (-3100 2600);
FORCEPROP 1 LAST WATTAGE 1/16W
J 2
(-3250 2525);
DISPLAY 0.319149 (-3250 2525);
DISPLAY INVISIBLE (-3250 2525);
FORCEPROP 1 LAST PATH I44
J 0
(-3400 2750);
DISPLAY 0.978723 (-3400 2750);
PAINT WHITE (-3400 2750);
DISPLAY INVISIBLE (-3400 2750);
FORCEPROP 1 LAST PART_NUMBER CS00002JB13
J 0
(-3425 2550);
DISPLAY 0.319149 (-3425 2550);
DISPLAY INVISIBLE (-3425 2550);
FORCEADD Q_RES..1
(-3350 2850);
FORCEPROP 1 LAST LOCATION R1180
J 0
(-3575 2875);
DISPLAY 0.638298 (-3575 2875);
FORCEPROP 0 LAST $SEC 1
J 0
(-3575 2925);
DISPLAY 0.680851 (-3575 2925);
PAINT MONO (-3575 2925);
DISPLAY INVISIBLE (-3575 2925);
FORCEPROP 0 LAST CDS_SEC 1
J 0
(-3575 2925);
DISPLAY 0.680851 (-3575 2925);
DISPLAY INVISIBLE (-3575 2925);
FORCEPROP 1 LASTPIN (-3450 2850) $PN 1
J 0
(-3438 2862);
DISPLAY 0.787234 (-3438 2862);
PAINT MONO (-3438 2862);
FORCEPROP 1 LASTPIN (-3250 2850) $PN 2
J 0
(-3288 2862);
DISPLAY 0.787234 (-3288 2862);
PAINT MONO (-3288 2862);
FORCEPROP 1 LAST VALUE 0
J 2
(-3200 2850);
DISPLAY 0.510638 (-3200 2850);
FORCEPROP 1 LAST TOLERANCE 5%
J 0
(-3175 2850);
DISPLAY 0.510638 (-3175 2850);
FORCEPROP 1 LAST MATERIAL EMPTY
J 0
(-3400 2800);
DISPLAY 0.510638 (-3400 2800);
PAINT RED (-3400 2800);
FORCEPROP 2 LAST CDS_LIB pure_quanta
J 0
(-3350 2850);
DISPLAY INVISIBLE (-3350 2850);
FORCEPROP 1 LAST WATTAGE 1/16W
J 2
(-3250 2775);
DISPLAY 0.319149 (-3250 2775);
DISPLAY INVISIBLE (-3250 2775);
FORCEPROP 1 LAST PACK_TYPE 0402LF
J 0
(-3100 2850);
DISPLAY 0.510638 (-3100 2850);
DISPLAY INVISIBLE (-3100 2850);
FORCEPROP 1 LAST PATH I45
J 0
(-3400 3000);
DISPLAY 0.978723 (-3400 3000);
PAINT WHITE (-3400 3000);
DISPLAY INVISIBLE (-3400 3000);
FORCEPROP 1 LAST PART_NUMBER CS00002JB13
J 0
(-3425 2800);
DISPLAY 0.319149 (-3425 2800);
DISPLAY INVISIBLE (-3425 2800);
FORCEADD OFFPAGE..1
R 2
(-1850 2600);
FORCEPROP 2 LAST $XR2 141 
J 0
(-1424 2600);
DISPLAY 0.638298 (-1424 2600);
PAINT MONO (-1424 2600);
FORCEPROP 2 LAST $XR1 140 
J 0
(-1544 2600);
DISPLAY 0.638298 (-1544 2600);
PAINT MONO (-1544 2600);
FORCEPROP 2 LAST $XR0 142 
J 0
(-1664 2600);
DISPLAY 0.638298 (-1664 2600);
PAINT MONO (-1664 2600);
FORCEPROP 2 LAST CDS_LIB standard
J 0
(-1850 2600);
DISPLAY INVISIBLE (-1850 2600);
FORCEPROP 1 LAST OFFPAGE TRUE
J 2
(-2175 2475);
DISPLAY 0.872340 (-2175 2475);
PAINT GREEN (-2175 2475);
DISPLAY INVISIBLE (-2175 2475);
FORCEPROP 1 LAST COMMENT_BODY TRUE
J 2
(-1975 2500);
DISPLAY 0.872340 (-1975 2500);
PAINT GREEN (-1975 2500);
DISPLAY INVISIBLE (-1975 2500);
FORCEPROP 2 LAST PATH I46
J 0
(-1675 2675);
DISPLAY 0.680851 (-1675 2675);
DISPLAY INVISIBLE (-1675 2675);
FORCEADD UNIVERSAL_GND..1
(-5700 3450);
FORCEPROP 3 LASTPIN (-5700 3500) SIG_NAME GND\g
J 0
(-5690 3510);
DISPLAY 0.659574 (-5690 3510);
PAINT MONO (-5690 3510);
DISPLAY INVISIBLE (-5690 3510);
FORCEPROP 2 LAST CDS_LIB pure_quanta_power
J 0
(-5700 3450);
PAINT MONO (-5700 3450);
DISPLAY INVISIBLE (-5700 3450);
FORCEPROP 1 LAST HDL_POWER GND
J 1
(-5675 3375);
DISPLAY 0.872340 (-5675 3375);
PAINT GREEN (-5675 3375);
DISPLAY INVISIBLE (-5675 3375);
FORCEPROP 1 LAST PATH I5
J 0
(-5625 3450);
DISPLAY 0.872340 (-5625 3450);
PAINT AQUA (-5625 3450);
DISPLAY INVISIBLE (-5625 3450);
FORCEADD PCA9617ADP..1
(-4775 3225);
FORCEPROP 1 LAST LOCATION U235
J 0
(-5049 3635);
DISPLAY 0.723404 (-5049 3635);
PAINT GREEN (-5049 3635);
FORCEPROP 0 LAST $SEC 1
J 0
(-5025 3775);
DISPLAY 0.680851 (-5025 3775);
PAINT MONO (-5025 3775);
DISPLAY INVISIBLE (-5025 3775);
FORCEPROP 0 LAST CDS_SEC 1
J 0
(-5025 3775);
DISPLAY 1.021277 (-5025 3775);
DISPLAY INVISIBLE (-5025 3775);
FORCEPROP 0 LASTPIN (-4350 3025) $PN 5
J 0
(-4340 3035);
DISPLAY 0.680851 (-4340 3035);
PAINT MONO (-4340 3035);
FORCEPROP 0 LASTPIN (-5200 3025) $PN 4
J 2
(-5210 3035);
DISPLAY 0.680851 (-5210 3035);
PAINT MONO (-5210 3035);
FORCEPROP 0 LASTPIN (-5200 3275) $PN 2
J 2
(-5210 3285);
DISPLAY 0.680851 (-5210 3285);
PAINT MONO (-5210 3285);
FORCEPROP 0 LASTPIN (-4350 3275) $PN 7
J 0
(-4340 3285);
DISPLAY 0.680851 (-4340 3285);
PAINT MONO (-4340 3285);
FORCEPROP 0 LASTPIN (-5200 3175) $PN 3
J 2
(-5210 3185);
DISPLAY 0.680851 (-5210 3185);
PAINT MONO (-5210 3185);
FORCEPROP 0 LASTPIN (-4350 3175) $PN 6
J 0
(-4340 3185);
DISPLAY 0.680851 (-4340 3185);
PAINT MONO (-4340 3185);
FORCEPROP 0 LASTPIN (-5200 3425) $PN 1
J 2
(-5210 3435);
DISPLAY 0.680851 (-5210 3435);
PAINT MONO (-5210 3435);
FORCEPROP 0 LASTPIN (-4350 3425) $PN 8
J 0
(-4340 3435);
DISPLAY 0.680851 (-4340 3435);
PAINT MONO (-4340 3435);
FORCEPROP 1 LAST MATERIAL IC
J 0
(-5049 3530);
DISPLAY 0.723404 (-5049 3530);
PAINT GREEN (-5049 3530);
FORCEPROP 2 LAST PART_TYPE SMLF
J 0
(-5025 3725);
DISPLAY 1.021277 (-5025 3725);
FORCEPROP 2 LAST VALUE PCA9617ADP
J 0
(-5025 3675);
DISPLAY 1.021277 (-5025 3675);
FORCEPROP 2 LAST CDS_LIB pure_quanta
J 0
(-4775 3225);
DISPLAY INVISIBLE (-4775 3225);
FORCEPROP 1 LAST CDS_LMAN_SYM_OUTLINE -275,300,275,-300
J 0
(-4775 3225);
DISPLAY 0.468085 (-4775 3225);
PAINT GREEN (-4775 3225);
DISPLAY INVISIBLE (-4775 3225);
FORCEPROP 1 LAST NEEDS_NO_SIZE TRUE
J 0
(-4500 2925);
DISPLAY 0.468085 (-4500 2925);
PAINT GREEN (-4500 2925);
DISPLAY INVISIBLE (-4500 2925);
FORCEPROP 1 LAST PATH I6
J 0
(-4775 3225);
DISPLAY 0.723404 (-4775 3225);
PAINT GREEN (-4775 3225);
DISPLAY INVISIBLE (-4775 3225);
FORCEPROP 1 LAST PART_NUMBER AL009617K02
J 0
(-5049 3585);
DISPLAY 0.723404 (-5049 3585);
PAINT GREEN (-5049 3585);
DISPLAY INVISIBLE (-5049 3585);
FORCEADD UNIVERSAL_POWER..1
(-5350 3975);
FORCEPROP 3 LASTPIN (-5350 3925) SIG_NAME P3V3_AUX\g
J 0
(-5340 3935);
DISPLAY 0.659574 (-5340 3935);
PAINT MONO (-5340 3935);
DISPLAY INVISIBLE (-5340 3935);
FORCEPROP 1 LAST HDL_POWER P3V3_AUX
J 1
(-5350 4025);
DISPLAY 0.872340 (-5350 4025);
PAINT GREEN (-5350 4025);
FORCEPROP 2 LAST CDS_LIB pure_quanta_power
J 0
(-5350 3975);
PAINT MONO (-5350 3975);
DISPLAY INVISIBLE (-5350 3975);
FORCEPROP 1 LAST PATH I7
J 0
(-5300 4000);
DISPLAY 0.872340 (-5300 4000);
PAINT AQUA (-5300 4000);
DISPLAY INVISIBLE (-5300 4000);
FORCEADD UNIVERSAL_GND..1
(-4025 3475);
FORCEPROP 3 LASTPIN (-4025 3525) SIG_NAME GND\g
J 0
(-4015 3535);
DISPLAY 0.659574 (-4015 3535);
PAINT MONO (-4015 3535);
DISPLAY INVISIBLE (-4015 3535);
FORCEPROP 2 LAST CDS_LIB pure_quanta_power
J 0
(-4025 3475);
DISPLAY INVISIBLE (-4025 3475);
FORCEPROP 1 LAST HDL_POWER GND
J 1
(-4000 3400);
DISPLAY 0.872340 (-4000 3400);
PAINT GREEN (-4000 3400);
DISPLAY INVISIBLE (-4000 3400);
FORCEPROP 1 LAST PATH I8
J 0
(-3950 3475);
DISPLAY 0.872340 (-3950 3475);
PAINT AQUA (-3950 3475);
DISPLAY INVISIBLE (-3950 3475);
FORCEADD Q_CAP..1
(-4025 3675);
FORCEPROP 1 LAST LOCATION C1861
J 0
(-3975 3775);
DISPLAY 0.978723 (-3975 3775);
FORCEPROP 0 LAST $SEC 1
J 0
(-3975 3825);
DISPLAY 0.680851 (-3975 3825);
PAINT MONO (-3975 3825);
DISPLAY INVISIBLE (-3975 3825);
FORCEPROP 0 LAST CDS_SEC 1
J 0
(-3975 3825);
DISPLAY 1.021277 (-3975 3825);
DISPLAY INVISIBLE (-3975 3825);
FORCEPROP 1 LASTPIN (-4025 3775) $PN 1
J 0
(-4015 3755);
DISPLAY 0.787234 (-4015 3755);
PAINT MONO (-4015 3755);
FORCEPROP 1 LASTPIN (-4025 3575) $PN 2
J 0
(-4015 3555);
DISPLAY 0.787234 (-4015 3555);
PAINT MONO (-4015 3555);
FORCEPROP 1 LAST VOLTAGE 25V
J 0
(-3975 3675);
DISPLAY 0.510638 (-3975 3675);
FORCEPROP 1 LAST VALUE 0.1UF
J 0
(-3975 3725);
DISPLAY 0.510638 (-3975 3725);
FORCEPROP 1 LAST TOLERANCE 10%
J 0
(-3975 3625);
DISPLAY 0.510638 (-3975 3625);
FORCEPROP 1 LAST PACK_TYPE 0402
J 0
(-3975 3475);
DISPLAY 0.510638 (-3975 3475);
FORCEPROP 1 LAST MATERIAL X7R
J 0
(-3975 3575);
DISPLAY 0.510638 (-3975 3575);
FORCEPROP 2 LAST CDS_LIB pure_quanta
J 0
(-4025 3675);
DISPLAY INVISIBLE (-4025 3675);
FORCEPROP 1 LAST PATH I9
J 0
(-3975 3825);
DISPLAY 0.978723 (-3975 3825);
PAINT WHITE (-3975 3825);
DISPLAY INVISIBLE (-3975 3825);
FORCEPROP 1 LAST PART_NUMBER CH4104K1B00
J 0
(-3975 3525);
DISPLAY 0.510638 (-3975 3525);
DISPLAY INVISIBLE (-3975 3525);
FORCEADD QUANTA_TITLE_BLOCK_C..1
(0 0);
FORCEPROP 0 LAST CDS_CON_LAST_MODIFIED Thu Sep 14 16:12:34 2023
J 0
(-1885 15);
DISPLAY INVISIBLE (-1885 15);
FORCEPROP 1 LAST CUSTOM_TXT_CDS <CON_LAST_MODIFIED>
J 0
(-1885 15);
DISPLAY 0.978723 (-1885 15);
FORCEPROP 2 LAST CUSTOM_TXT_CDS <XR_PAGE_TITLE>
J 0
(-7890 5250);
DISPLAY 0.638298 (-7890 5250);
PAINT PINK (-7890 5250);
DISPLAY INVISIBLE (-7890 5250);
FORCEPROP 1 LAST CUSTOM_TXT_CDS <NAME_2>
J 0
(-3175 50);
FORCEPROP 1 LAST CUSTOM_TXT_CDS <NAME_1>
J 0
(-3175 175);
FORCEPROP 1 LAST CUSTOM_TXT_CDS <Q_NUMBER>
J 0
(-1403 103);
DISPLAY 1.212766 (-1403 103);
FORCEPROP 1 LAST CUSTOM_TXT_CDS <Q_PROJ>
J 0
(-2382 102);
DISPLAY 1.212766 (-2382 102);
FORCEPROP 1 LAST CUSTOM_TXT_CDS <Q_REV>
J 0
(-184 103);
DISPLAY 1.212766 (-184 103);
FORCEPROP 1 LAST CUSTOM_TXT_CDS <CON_PAGE_NUM> OF <CON_TOTAL_PAGES>
J 0
(-446 18);
DISPLAY 0.978723 (-446 18);
FORCEPROP 1 LAST Q_TITLE SMBUS - ISOLATED
J 0
(-9366 26);
DISPLAY 2.446809 (-9366 26);
PAINT GREEN (-9366 26);
FORCEPROP 2 LAST PAGE_BORDER TRUE
J 0
(-7890 5250);
DISPLAY 0.638298 (-7890 5250);
PAINT PINK (-7890 5250);
DISPLAY INVISIBLE (-7890 5250);
FORCEPROP 1 LAST CDS_LMAN_SYM_OUTLINE -9475,6775,100,-125
J 0
(0 0);
DISPLAY 0.468085 (0 0);
PAINT GREEN (0 0);
DISPLAY INVISIBLE (0 0);
FORCEPROP 2 LAST CDS_LIB pure_quanta
J 0
(0 0);
DISPLAY INVISIBLE (0 0);
FORCEPROP 2 LAST CDS_XR_PAGE_TITLE CR-248 : @T6G_MB_LIB.T6G(SCH_1):PAGE248
J 0
(-7890 5250);
DISPLAY 0.638298 (-7890 5250);
PAINT PINK (-7890 5250);
DISPLAY INVISIBLE (-7890 5250);
FORCEPROP 1 LAST Q_DEPT BU9
J 1
(-3763 49);
DISPLAY 1.957447 (-3763 49);
PAINT GREEN (-3763 49);
DISPLAY INVISIBLE (-3763 49);
FORCEPROP 1 LAST COMMENT_BODY TRUE
J 0
(12 -13);
DISPLAY 0.978723 (12 -13);
PAINT GREEN (12 -13);
DISPLAY INVISIBLE (12 -13);
FORCEADD DNS..2
(-3425 4850);
PAINT RED (-3425 4850);
FORCEPROP 2 LAST CDS_LIB mstr_misc
J 0
(-3425 4850);
DISPLAY INVISIBLE (-3425 4850);
FORCEPROP 1 LAST COMMENT_BODY TRUE
J 0
(-3425 4850);
DISPLAY INVISIBLE (-3425 4850);
FORCEADD DNS..2
(-3425 4650);
PAINT RED (-3425 4650);
FORCEPROP 2 LAST CDS_LIB mstr_misc
J 0
(-3425 4650);
DISPLAY INVISIBLE (-3425 4650);
FORCEPROP 1 LAST COMMENT_BODY TRUE
J 0
(-3425 4650);
DISPLAY INVISIBLE (-3425 4650);
FORCEADD DNS..2
(-3350 3050);
PAINT RED (-3350 3050);
FORCEPROP 2 LAST CDS_LIB mstr_misc
J 0
(-3350 3050);
DISPLAY INVISIBLE (-3350 3050);
FORCEPROP 1 LAST COMMENT_BODY TRUE
J 0
(-3350 3050);
DISPLAY INVISIBLE (-3350 3050);
FORCEADD DNS..2
(-3325 2850);
PAINT RED (-3325 2850);
FORCEPROP 2 LAST CDS_LIB mstr_misc
J 0
(-3325 2850);
DISPLAY INVISIBLE (-3325 2850);
FORCEPROP 1 LAST COMMENT_BODY TRUE
J 0
(-3325 2850);
DISPLAY INVISIBLE (-3325 2850);
WIRE 16 -1 (-5675 5400)(-5675 5325);
WIRE 16 -1 (-4000 5400)(-4000 5350);
WIRE 16 -1 (-5700 3575)(-5700 3500);
WIRE 16 -1 (-4025 3575)(-4025 3525);
WIRE 16 -1 (-4350 3275)(-3200 3275);
FORCEPROP 0 LAST CDS_PHYS_NET_NAME SMB_OCP_V3_2_3V3AUX_BUF_SCL
J 0
(-4310 3323);
PAINT MONO (-4310 3323);
DISPLAY INVISIBLE (-4310 3323);
FORCEPROP 2 LAST SIG_NAME SMB_OCP_V3_2_3V3AUX_BUF_SCL
J 0
(-4210 3285);
DISPLAY 0.510638 (-4210 3285);
PAINT WHITE (-4210 3285);
WIRE 16 -1 (-3200 3275)(-2425 3275);
WIRE 16 -1 (-3200 3525)(-3200 3275);
WIRE 16 -1 (-2950 3725)(-2950 3850);
WIRE 16 -1 (-3200 3850)(-2950 3850);
WIRE 16 -1 (-3200 3725)(-3200 3850);
WIRE 16 -1 (-3200 3850)(-3200 3900);
WIRE 16 -1 (-2950 3525)(-2950 3175);
WIRE 16 -1 (-2950 3175)(-2425 3175);
WIRE 16 -1 (-4350 3175)(-2950 3175);
FORCEPROP 0 LAST CDS_PHYS_NET_NAME SMB_OCP_V3_2_3V3AUX_BUF_SDA
J 0
(-4310 3223);
PAINT MONO (-4310 3223);
DISPLAY INVISIBLE (-4310 3223);
FORCEPROP 2 LAST SIG_NAME SMB_OCP_V3_2_3V3AUX_BUF_SDA
J 0
(-4210 3185);
DISPLAY 0.510638 (-4210 3185);
PAINT WHITE (-4210 3185);
WIRE 16 -1 (-3275 3025)(-2425 3025);
FORCEPROP 0 LAST CDS_PHYS_NET_NAME HP_LVC3_OCP_V3_2_EN
J 0
(-2610 3067);
PAINT MONO (-2610 3067);
DISPLAY INVISIBLE (-2610 3067);
FORCEPROP 2 LAST SIG_NAME P3V3_OCP_V3_2_EN_R
J 0
(-2935 3035);
DISPLAY 0.553191 (-2935 3035);
PAINT WHITE (-2935 3035);
FORCEPROP 0 LAST $PHYS_NET_NAME RST_PCIE_M2_N
J 0
(-2610 3114);
PAINT MONO (-2610 3114);
DISPLAY INVISIBLE (-2610 3114);
WIRE 16 -1 (-3250 2850)(-1900 2850);
FORCEPROP 2 LAST SIG_NAME HP_LVC3_OCP_V3_2_P12V_PWRGD
J 0
(-2935 2860);
DISPLAY 0.680851 (-2935 2860);
WIRE 16 -1 (-3350 4650)(-2050 4650);
FORCEPROP 2 LAST SIG_NAME HP_LVC3_OCP_V3_1_P12V_PWRGD
J 0
(-3035 4660);
DISPLAY 0.680851 (-3035 4660);
WIRE 16 -1 (-3250 2600)(-1900 2600);
FORCEPROP 2 LAST SIG_NAME P12V_OCP_V3_2_BUF_EN_R
J 0
(-2885 2610);
DISPLAY 0.680851 (-2885 2610);
WIRE 16 -1 (-3350 4475)(-2050 4475);
FORCEPROP 2 LAST SIG_NAME P12V_OCP_SFF_BUF_EN_R
J 0
(-3010 4485);
DISPLAY 0.680851 (-3010 4485);
WIRE 16 -1 (-4225 3850)(-4025 3850);
WIRE 16 -1 (-4225 3925)(-4225 3850);
WIRE 16 -1 (-4225 3850)(-4225 3425);
WIRE 16 -1 (-4025 3850)(-4025 3775);
WIRE 16 -1 (-4225 3425)(-4350 3425);
WIRE 16 -1 (-3575 2850)(-3450 2850);
WIRE 16 -1 (-3575 3025)(-3575 2850);
WIRE 16 -1 (-3575 2850)(-3575 2600);
WIRE 16 -1 (-3575 2600)(-3450 2600);
WIRE 16 -1 (-3475 3025)(-3575 3025);
FORCEPROP 0 LAST $PHYS_NET_NAME RST_PCIE_M2_N
J 0
(-3585 3114);
PAINT MONO (-3585 3114);
DISPLAY INVISIBLE (-3585 3114);
WIRE 16 -1 (-3575 3025)(-4350 3025);
FORCEPROP 0 LAST CDS_PHYS_NET_NAME HP_LVC3_OCP_V3_2_R_EN
J 0
(-3585 3067);
PAINT MONO (-3585 3067);
DISPLAY INVISIBLE (-3585 3067);
FORCEPROP 2 LAST SIG_NAME HP_LVC3_OCP_V3_2_R_EN
J 0
(-4210 3035);
DISPLAY 0.553191 (-4210 3035);
PAINT WHITE (-4210 3035);
FORCEPROP 2 LASTPROP $XRERR UNIQUE?
J 0
(-4450 3035);
DISPLAY 0.638298 (-4450 3035);
PAINT MONO (-4450 3035);
DISPLAY INVISIBLE (-4450 3035);
WIRE 16 -1 (-5275 4850)(-5175 4850);
WIRE 16 -1 (-5275 4675)(-5275 4850);
WIRE 16 -1 (-5325 5675)(-5325 5250);
WIRE 16 -1 (-5325 5675)(-5675 5675);
WIRE 16 -1 (-5325 5675)(-5325 5750);
WIRE 16 -1 (-5325 5250)(-5175 5250);
WIRE 16 -1 (-5675 5600)(-5675 5675);
WIRE 16 -1 (-4200 5675)(-4000 5675);
WIRE 16 -1 (-4200 5750)(-4200 5675);
WIRE 16 -1 (-4200 5675)(-4200 5250);
WIRE 16 -1 (-4000 5675)(-4000 5600);
WIRE 16 -1 (-4200 5250)(-4325 5250);
WIRE 16 -1 (-2775 5550)(-2775 5675);
WIRE 16 -1 (-3025 5675)(-2775 5675);
WIRE 16 -1 (-3025 5550)(-3025 5675);
WIRE 16 -1 (-3025 5675)(-3025 5725);
WIRE 16 -1 (-5300 3025)(-5200 3025);
WIRE 16 -1 (-5300 2850)(-5300 3025);
WIRE 16 -1 (-5350 3850)(-5350 3425);
WIRE 16 -1 (-5350 3850)(-5700 3850);
WIRE 16 -1 (-5350 3850)(-5350 3925);
WIRE 16 -1 (-5350 3425)(-5200 3425);
WIRE 16 -1 (-5700 3775)(-5700 3850);
WIRE 16 -1 (-3025 5350)(-3025 5100);
WIRE 16 -1 (-3025 5100)(-2300 5100);
WIRE 16 -1 (-4325 5100)(-3025 5100);
FORCEPROP 0 LAST CDS_PHYS_NET_NAME SMB_OCP_SFF_3V3AUX_BUF_SCL
J 0
(-4285 5148);
PAINT MONO (-4285 5148);
DISPLAY INVISIBLE (-4285 5148);
FORCEPROP 2 LAST SIG_NAME SMB_OCP_SFF_3V3AUX_BUF_SCL
J 0
(-4185 5110);
DISPLAY 0.510638 (-4185 5110);
PAINT WHITE (-4185 5110);
WIRE 16 -1 (-3350 4850)(-2025 4850);
FORCEPROP 0 LAST CDS_PHYS_NET_NAME HP_LVC3_OCP_V3_1_EN
J 0
(-2210 4892);
PAINT MONO (-2210 4892);
DISPLAY INVISIBLE (-2210 4892);
FORCEPROP 2 LAST SIG_NAME P3V3_OCP_SFF_EN_R
J 0
(-2960 4860);
DISPLAY 0.553191 (-2960 4860);
PAINT WHITE (-2960 4860);
FORCEPROP 0 LAST $PHYS_NET_NAME RST_PCIE_M2_N
J 0
(-2210 4939);
PAINT MONO (-2210 4939);
DISPLAY INVISIBLE (-2210 4939);
WIRE 16 -1 (-2300 5000)(-2775 5000);
WIRE 16 -1 (-2775 5350)(-2775 5000);
WIRE 16 -1 (-4325 5000)(-2775 5000);
FORCEPROP 0 LAST CDS_PHYS_NET_NAME SMB_OCP_SFF_3V3AUX_BUF_SDA
J 0
(-4285 5048);
PAINT MONO (-4285 5048);
DISPLAY INVISIBLE (-4285 5048);
FORCEPROP 2 LAST SIG_NAME SMB_OCP_SFF_3V3AUX_BUF_SDA
J 0
(-4185 5010);
DISPLAY 0.510638 (-4185 5010);
PAINT WHITE (-4185 5010);
WIRE 16 -1 (-3750 4475)(-3550 4475);
WIRE 16 -1 (-3750 4650)(-3750 4475);
WIRE 16 -1 (-3750 4650)(-3550 4650);
WIRE 16 -1 (-3750 4850)(-3750 4650);
WIRE 16 -1 (-3550 4850)(-3750 4850);
FORCEPROP 0 LAST CDS_PHYS_NET_NAME HP_LVC3_OCP_V3_1_R_EN
J 0
(-3660 4892);
PAINT MONO (-3660 4892);
DISPLAY INVISIBLE (-3660 4892);
FORCEPROP 0 LAST $PHYS_NET_NAME RST_PCIE_M2_N
J 0
(-3660 4939);
PAINT MONO (-3660 4939);
DISPLAY INVISIBLE (-3660 4939);
WIRE 16 -1 (-3750 4850)(-4325 4850);
FORCEPROP 2 LAST SIG_NAME HP_LVC3_OCP_V3_1_R_EN
J 0
(-4285 4860);
DISPLAY 0.553191 (-4285 4860);
PAINT WHITE (-4285 4860);
FORCEPROP 2 LASTPROP $XRERR UNIQUE?
J 0
(-4525 4860);
DISPLAY 0.638298 (-4525 4860);
PAINT MONO (-4525 4860);
DISPLAY INVISIBLE (-4525 4860);
WIRE 16 -1 (-6150 3275)(-5200 3275);
FORCEPROP 0 LAST CDS_PHYS_NET_NAME SMB_OCP_V3_2_3V3AUX_SCL
J 0
(-6110 3323);
PAINT MONO (-6110 3323);
DISPLAY INVISIBLE (-6110 3323);
FORCEPROP 2 LAST SIG_NAME SMB_OCP_V3_2_3V3AUX_SCL
J 0
(-5985 3285);
DISPLAY 0.510638 (-5985 3285);
PAINT WHITE (-5985 3285);
WIRE 16 -1 (-6125 5100)(-5175 5100);
FORCEPROP 0 LAST CDS_PHYS_NET_NAME SMB_OCP_SFF_3V3AUX_SCL
J 0
(-6085 5148);
PAINT MONO (-6085 5148);
DISPLAY INVISIBLE (-6085 5148);
FORCEPROP 2 LAST SIG_NAME SMB_OCP_SFF_3V3AUX_SCL
J 0
(-5960 5110);
DISPLAY 0.510638 (-5960 5110);
PAINT WHITE (-5960 5110);
WIRE 16 -1 (-6125 5000)(-5175 5000);
FORCEPROP 0 LAST CDS_PHYS_NET_NAME SMB_OCP_SFF_3V3AUX_SDA
J 0
(-6085 5048);
PAINT MONO (-6085 5048);
DISPLAY INVISIBLE (-6085 5048);
FORCEPROP 2 LAST SIG_NAME SMB_OCP_SFF_3V3AUX_SDA
J 0
(-5960 5010);
DISPLAY 0.510638 (-5960 5010);
PAINT WHITE (-5960 5010);
WIRE 16 -1 (-6150 3175)(-5200 3175);
FORCEPROP 0 LAST CDS_PHYS_NET_NAME SMB_OCP_V3_2_3V3AUX_SDA
J 0
(-6110 3223);
PAINT MONO (-6110 3223);
DISPLAY INVISIBLE (-6110 3223);
FORCEPROP 2 LAST SIG_NAME SMB_OCP_V3_2_3V3AUX_SDA
J 0
(-5985 3185);
DISPLAY 0.510638 (-5985 3185);
PAINT WHITE (-5985 3185);
DOT 1 (-3575 2850);
DOT 1 (-3025 5100);
DOT 1 (-3200 3850);
DOT 1 (-2950 3175);
DOT 1 (-3575 3025);
DOT 1 (-3750 4850);
DOT 1 (-3025 5675);
DOT 1 (-4200 5675);
DOT 1 (-5325 5675);
DOT 1 (-4225 3850);
DOT 1 (-5350 3850);
DOT 1 (-2775 5000);
DOT 1 (-3750 4650);
DOT 1 (-3200 3275);
FORCENOTE
FROM CPLD
(-1925 4925) 0;
DISPLAY LEFT (-1925 4925);
DISPLAY 1.021277 (-1925 4925);
FORCENOTE
FROM OCP_12V_HSC PWRGD
(-1675 2700) 0;
DISPLAY LEFT (-1675 2700);
DISPLAY 1.021277 (-1675 2700);
FORCENOTE
FROM CPLD
(-1650 3075) 0;
DISPLAY LEFT (-1650 3075);
DISPLAY 1.021277 (-1650 3075);
FORCENOTE
FROM OCP_12V_HSC PWRGD
(-1950 4550) 0;
DISPLAY LEFT (-1950 4550);
DISPLAY 1.021277 (-1950 4550);
FORCENOTE
FROM OCP HSC ENABLE
(-1700 2475) 0;
DISPLAY LEFT (-1700 2475);
DISPLAY 1.021277 (-1700 2475);
FORCENOTE
FROM OCP HSC ENABLE
(-1975 4375) 0;
DISPLAY LEFT (-1975 4375);
DISPLAY 1.021277 (-1975 4375);
QUIT
